FILE_TYPE=LIBRARY_PARTS;
primitive 'SHUNT','SHUNT2_SH0201','SHUNT2_SH01005';
  pin
    'A':
      PIN_NUMBER='(1)';
      PIN_TYPE='ANALOG';
      NO_LOAD_CHECK='Both';
      NO_IO_CHECK='Both';
      NO_ASSERT_CHECK='TRUE';
      NO_DIR_CHECK='TRUE';
      ALLOW_CONNECT='TRUE';
    'B':
      PIN_NUMBER='(2)';
      PIN_TYPE='ANALOG';
      NO_LOAD_CHECK='Both';
      NO_IO_CHECK='Both';
      NO_ASSERT_CHECK='TRUE';
      NO_DIR_CHECK='TRUE';
      ALLOW_CONNECT='TRUE';
  end_pin;
  body
    PART_NAME='SHUNT';
    PHYS_DES_PREFIX='SH';
  end_body;
end_primitive;

END.

